(kicad_pcb
	(version 20260206)
	(generator "pcbnew")
	(generator_version "10.0")
	(general
		(thickness 1.6)
		(legacy_teardrops no)
	)
	(paper "A4")
	(title_block
		(title "v1-chassis-manager — T6M_CM_d_v01_1031_1645.brd")
		(comment 1 "Open CloudServer (Microsoft) / footprints 836-837 of 2512")
	)
	(layers
		(0 "F.Cu" signal "TOP")
		(4 "In1.Cu" signal "GND1")
		(6 "In2.Cu" signal "IN1")
		(8 "In3.Cu" signal "VCC1")
		(10 "In4.Cu" signal "VCC2")
		(12 "In5.Cu" signal "GND2")
		(14 "In6.Cu" signal "IN2")
		(16 "In7.Cu" signal "IN3")
		(18 "In8.Cu" signal "GND3")
		(2 "B.Cu" signal "BOTTOM")
		(9 "F.Adhes" user "F.Adhesive")
		(11 "B.Adhes" user "B.Adhesive")
		(13 "F.Paste" user "Package Geometry/Pastemask Top")
		(15 "B.Paste" user "Package Geometry/Pastemask Bottom")
		(5 "F.SilkS" user "Ref Des/Silkscreen Top")
		(7 "B.SilkS" user "Ref Des/Silkscreen Bottom")
		(1 "F.Mask" user "Board Geometry/Soldermask Top")
		(3 "B.Mask" user "Board Geometry/Soldermask Bottom")
		(17 "Dwgs.User" user "User.Drawings")
		(19 "Cmts.User" user "User.Comments")
		(21 "Eco1.User" user "User.Eco1")
		(23 "Eco2.User" user "User.Eco2")
		(25 "Edge.Cuts" user "Board Geometry/Outline")
		(27 "Margin" user)
		(31 "F.CrtYd" user "Package Geometry/Place Bound Top")
		(29 "B.CrtYd" user "Package Geometry/Place Bound Bottom")
		(35 "F.Fab" user "Ref Des/Assembly Top")
		(33 "B.Fab" user "Ref Des/Assembly Bottom")
	)
	(footprint ""
		(layer "F.Cu")
		(at 144.916652 -145.21815)
		(property "Reference" "R277"
			(at -0.704088 18.560288 0)
			(unlocked yes)
			(layer "F.SilkS")
			(effects
				(font
					(size 0.7874 0.5842)
					(thickness 0.1524)
				)
				(justify left)
			)
		)
		(property "Value" ""
			(at 0 0 0)
			(layer "F.Fab")
			(effects
				(font
					(size 1.27 1.27)
				)
			)
		)
		(duplicate_pad_numbers_are_jumpers no)
		(fp_line
			(start -0.7874 -0.4064)
			(end 0.7874 -0.4064)
			(stroke
				(width 0.1524)
				(type default)
			)
			(layer "F.SilkS")
		)
		(fp_line
			(start -0.7874 0.4064)
			(end -0.7874 -0.4064)
			(stroke
				(width 0.1524)
				(type default)
			)
			(layer "F.SilkS")
		)
		(fp_line
			(start 0.7874 -0.4064)
			(end 0.7874 0.4064)
			(stroke
				(width 0.1524)
				(type default)
			)
			(layer "F.SilkS")
		)
		(fp_line
			(start 0.7874 0.4064)
			(end -0.7874 0.4064)
			(stroke
				(width 0.1524)
				(type default)
			)
			(layer "F.SilkS")
		)
		(fp_poly
			(pts
				(xy -0.508 0.2794) (xy -0.508 0.2286) (xy -0.635 0.2286) (xy -0.635 -0.254) (xy -0.5334 -0.254)
				(xy -0.5334 -0.2794) (xy 0.5334 -0.2794) (xy 0.5334 -0.254) (xy 0.635 -0.254) (xy 0.635 0.254) (xy 0.5334 0.254)
				(xy 0.5334 0.2794)
			)
			(stroke
				(width 0)
				(type default)
			)
			(fill no)
			(layer "F.CrtYd")
		)
		(pad "1" smd rect
			(at 0.40005 0)
			(size 0.4572 0.508)
			(layers "F.Cu" "F.Mask" "F.Paste")
			(net "GND")
		)
		(pad "2" smd rect
			(at -0.40005 0)
			(size 0.4572 0.508)
			(layers "F.Cu" "F.Mask" "F.Paste")
			(net "PCIE_SW_P0_CTCDIS")
		)
	)
	(footprint ""
		(layer "F.Cu")
		(at 121.50598 -27.62758 -90)
		(property "Reference" "D6"
			(at 0.964184 1.317752 90)
			(unlocked yes)
			(layer "F.SilkS")
			(effects
				(font
					(size 0.7874 0.5842)
					(thickness 0.1524)
				)
				(justify left)
			)
		)
		(property "Value" ""
			(at 0 0 270)
			(layer "F.Fab")
			(effects
				(font
					(size 1.27 1.27)
				)
			)
		)
		(duplicate_pad_numbers_are_jumpers no)
		(fp_line
			(start -1.651 0.6858)
			(end -1.651 -0.6858)
			(stroke
				(width 0.1524)
				(type default)
			)
			(layer "F.SilkS")
		)
		(fp_line
			(start 1.651 0.6858)
			(end -1.651 0.6858)
			(stroke
				(width 0.1524)
				(type default)
			)
			(layer "F.SilkS")
		)
		(fp_line
			(start 1.9558 0.6858)
			(end 1.9558 -0.6858)
			(stroke
				(width 0.1524)
				(type default)
			)
			(layer "F.SilkS")
		)
		(fp_line
			(start 2.1082 0.6858)
			(end 1.651 0.6858)
			(stroke
				(width 0.1524)
				(type default)
			)
			(layer "F.SilkS")
		)
		(fp_line
			(start -0.299974 0.500126)
			(end 0.199898 0)
			(stroke
				(width 0.1524)
				(type default)
			)
			(layer "F.SilkS")
		)
		(fp_line
			(start 0.199898 0)
			(end -0.299974 -0.500126)
			(stroke
				(width 0.1524)
				(type default)
			)
			(layer "F.SilkS")
		)
		(fp_line
			(start -0.299974 -0.500126)
			(end -0.299974 0.500126)
			(stroke
				(width 0.1524)
				(type default)
			)
			(layer "F.SilkS")
		)
		(fp_line
			(start 0.299974 -0.500126)
			(end 0.299974 0.500126)
			(stroke
				(width 0.1524)
				(type default)
			)
			(layer "F.SilkS")
		)
		(fp_line
			(start -1.651 -0.6858)
			(end 1.651 -0.6858)
			(stroke
				(width 0.1524)
				(type default)
			)
			(layer "F.SilkS")
		)
		(fp_line
			(start 1.651 -0.6858)
			(end 1.651 0.6858)
			(stroke
				(width 0.1524)
				(type default)
			)
			(layer "F.SilkS")
		)
		(fp_line
			(start 1.8034 -0.6858)
			(end 1.8034 0.6858)
			(stroke
				(width 0.1524)
				(type default)
			)
			(layer "F.SilkS")
		)
		(fp_line
			(start 2.1082 -0.6858)
			(end 2.1082 0.6858)
			(stroke
				(width 0.1524)
				(type default)
			)
			(layer "F.SilkS")
		)
		(fp_line
			(start 2.1082 -0.6858)
			(end 1.651 -0.6858)
			(stroke
				(width 0.1524)
				(type default)
			)
			(layer "F.SilkS")
		)
		(fp_rect
			(start -1.4986 0.6858)
			(end 1.4986 -0.6858)
			(stroke
				(width 0)
				(type default)
			)
			(fill no)
			(layer "F.CrtYd")
		)
		(pad "1" smd rect
			(at -1.0922 0 90)
			(size 0.8128 0.8636)
			(layers "F.Cu" "F.Mask" "F.Paste")
			(net "P3V3_RTC_NODE1")
		)
		(pad "2" smd rect
			(at 1.0922 0 270)
			(size 0.8128 0.8636)
			(layers "F.Cu" "F.Mask" "F.Paste")
			(net "SIO_VBAT")
		)
	)
)
